(kicad_pcb
	(version 20260206)
	(generator "pcbnew")
	(generator_version "10.0")
	(general
		(thickness 1.6)
		(legacy_teardrops no)
	)
	(paper "A4")
	(title_block
		(title "Bryce Canyon_IOM_M2_16342-2_OCP.brd")
		(comment 1 "Bryce Canyon / footprints 483-489 of 1146")
	)
	(layers
		(0 "F.Cu" signal "TOP")
		(4 "In1.Cu" signal "L2GND")
		(6 "In2.Cu" signal "L3")
		(8 "In3.Cu" signal "L4VCC")
		(10 "In4.Cu" signal "L5VCC")
		(12 "In5.Cu" signal "L6")
		(14 "In6.Cu" signal "L7GND")
		(2 "B.Cu" signal "BOTTOM")
		(9 "F.Adhes" user "F.Adhesive")
		(11 "B.Adhes" user "B.Adhesive")
		(13 "F.Paste" user "Package Geometry/Pastemask Top")
		(15 "B.Paste" user "Package Geometry/Pastemask Bottom")
		(5 "F.SilkS" user "Ref Des/Silkscreen Top")
		(7 "B.SilkS" user "Ref Des/Silkscreen Bottom")
		(1 "F.Mask" user "Board Geometry/Soldermask Top")
		(3 "B.Mask" user "Board Geometry/Soldermask Bottom")
		(17 "Dwgs.User" user "User.Drawings")
		(19 "Cmts.User" user "User.Comments")
		(21 "Eco1.User" user "User.Eco1")
		(23 "Eco2.User" user "User.Eco2")
		(25 "Edge.Cuts" user "Board Geometry/Outline")
		(27 "Margin" user)
		(31 "F.CrtYd" user "Package Geometry/Place Bound Top")
		(29 "B.CrtYd" user "Package Geometry/Place Bound Bottom")
		(35 "F.Fab" user "Ref Des/Assembly Top")
		(33 "B.Fab" user "Ref Des/Assembly Bottom")
	)
	(footprint ""
		(layer "F.Cu")
		(at 58.928 -162.7886 180)
		(property "Reference" "R410"
			(at 0 0 180)
			(layer "F.SilkS")
			(hide yes)
			(effects
				(font
					(size 1.27 1.27)
				)
			)
		)
		(property "Value" "1KR2F-3-GP"
			(at 0.064008 -3.993896 180)
			(unlocked yes)
			(layer "F.Fab")
			(hide yes)
			(effects
				(font
					(size 1.016 1.016)
					(thickness 0.1524)
				)
			)
		)
		(property "Device Type" "R402H16"
			(at 0.064008 -5.517896 180)
			(unlocked yes)
			(layer "F.Fab")
			(hide yes)
			(effects
				(font
					(size 1.016 1.016)
					(thickness 0.1524)
				)
			)
		)
		(duplicate_pad_numbers_are_jumpers no)
		(fp_line
			(start 0.508 -0.9398)
			(end -0.508 -0.9398)
			(stroke
				(width 0.1524)
				(type default)
			)
			(layer "F.SilkS")
		)
		(fp_line
			(start -0.508 -0.9398)
			(end -0.508 0.9398)
			(stroke
				(width 0.1524)
				(type default)
			)
			(layer "F.SilkS")
		)
		(fp_rect
			(start -0.508 0.9398)
			(end 0.508 -0.9398)
			(stroke
				(width 0)
				(type default)
			)
			(fill no)
			(layer "F.CrtYd")
		)
		(fp_rect
			(start -0.508 0.9398)
			(end 0.508 -0.9398)
			(stroke
				(width 0)
				(type default)
			)
			(fill no)
			(layer "F.Fab")
		)
		(pad "1" smd custom
			(at 0 -0.4445 180)
			(size 0.1397 0.1397)
			(layers "F.Cu" "F.Mask" "F.Paste")
			(net "ADC_P3V3_STBY")
			(options
				(clearance outline)
				(anchor circle)
			)
			(primitives
				(gr_poly
					(pts
						(arc
							(start -0.1778 -0.2794)
							(mid -0.249642 -0.249642)
							(end -0.2794 -0.1778)
						)
						(arc
							(start -0.2794 0.1778)
							(mid -0.249642 0.249642)
							(end -0.1778 0.2794)
						)
						(arc
							(start 0.1778 0.2794)
							(mid 0.249642 0.249642)
							(end 0.2794 0.1778)
						)
						(arc
							(start 0.2794 -0.1778)
							(mid 0.249642 -0.249642)
							(end 0.1778 -0.2794)
						)
					)
					(width 0)
					(fill yes)
				)
			)
		)
		(pad "2" smd custom
			(at 0 0.4445 180)
			(size 0.1397 0.1397)
			(layers "F.Cu" "F.Mask" "F.Paste")
			(net "GND")
			(options
				(clearance outline)
				(anchor circle)
			)
			(primitives
				(gr_poly
					(pts
						(arc
							(start -0.1778 -0.2794)
							(mid -0.249642 -0.249642)
							(end -0.2794 -0.1778)
						)
						(arc
							(start -0.2794 0.1778)
							(mid -0.249642 0.249642)
							(end -0.1778 0.2794)
						)
						(arc
							(start 0.1778 0.2794)
							(mid 0.249642 0.249642)
							(end 0.2794 0.1778)
						)
						(arc
							(start 0.2794 -0.1778)
							(mid 0.249642 -0.249642)
							(end 0.1778 -0.2794)
						)
					)
					(width 0)
					(fill yes)
				)
			)
		)
	)
	(footprint ""
		(layer "F.Cu")
		(at 37.9476 -158.7246)
		(property "Reference" "R317"
			(at 0 0 0)
			(layer "F.SilkS")
			(hide yes)
			(effects
				(font
					(size 1.27 1.27)
				)
			)
		)
		(property "Value" "0R2J-2-GP"
			(at 0.064008 -3.993896 0)
			(unlocked yes)
			(layer "F.Fab")
			(hide yes)
			(effects
				(font
					(size 1.016 1.016)
					(thickness 0.1524)
				)
			)
		)
		(property "Device Type" "R402H16"
			(at 0.064008 -5.517896 0)
			(unlocked yes)
			(layer "F.Fab")
			(hide yes)
			(effects
				(font
					(size 1.016 1.016)
					(thickness 0.1524)
				)
			)
		)
		(duplicate_pad_numbers_are_jumpers no)
		(fp_line
			(start -0.508 -0.9398)
			(end -0.508 0.9398)
			(stroke
				(width 0.1524)
				(type default)
			)
			(layer "F.SilkS")
		)
		(fp_line
			(start 0.508 -0.9398)
			(end -0.508 -0.9398)
			(stroke
				(width 0.1524)
				(type default)
			)
			(layer "F.SilkS")
		)
		(fp_rect
			(start -0.508 0.9398)
			(end 0.508 -0.9398)
			(stroke
				(width 0)
				(type default)
			)
			(fill no)
			(layer "F.CrtYd")
		)
		(fp_rect
			(start -0.508 0.9398)
			(end 0.508 -0.9398)
			(stroke
				(width 0)
				(type default)
			)
			(fill no)
			(layer "F.Fab")
		)
		(pad "1" smd custom
			(at 0 -0.4445)
			(size 0.1397 0.1397)
			(layers "F.Cu" "F.Mask" "F.Paste")
			(net "PWM_OUT_ZONE_C")
			(options
				(clearance outline)
				(anchor circle)
			)
			(primitives
				(gr_poly
					(pts
						(arc
							(start -0.1778 -0.2794)
							(mid -0.249642 -0.249642)
							(end -0.2794 -0.1778)
						)
						(arc
							(start -0.2794 0.1778)
							(mid -0.249642 0.249642)
							(end -0.1778 0.2794)
						)
						(arc
							(start 0.1778 0.2794)
							(mid 0.249642 0.249642)
							(end 0.2794 0.1778)
						)
						(arc
							(start 0.2794 -0.1778)
							(mid 0.249642 -0.249642)
							(end 0.1778 -0.2794)
						)
					)
					(width 0)
					(fill yes)
				)
			)
		)
		(pad "2" smd custom
			(at 0 0.4445)
			(size 0.1397 0.1397)
			(layers "F.Cu" "F.Mask" "F.Paste")
			(net "FAN_PWM0_BMC")
			(options
				(clearance outline)
				(anchor circle)
			)
			(primitives
				(gr_poly
					(pts
						(arc
							(start -0.1778 -0.2794)
							(mid -0.249642 -0.249642)
							(end -0.2794 -0.1778)
						)
						(arc
							(start -0.2794 0.1778)
							(mid -0.249642 0.249642)
							(end -0.1778 0.2794)
						)
						(arc
							(start 0.1778 0.2794)
							(mid 0.249642 0.249642)
							(end 0.2794 0.1778)
						)
						(arc
							(start 0.2794 -0.1778)
							(mid 0.249642 -0.249642)
							(end 0.1778 -0.2794)
						)
					)
					(width 0)
					(fill yes)
				)
			)
		)
	)
	(footprint ""
		(layer "F.Cu")
		(at 85.451442 -172.077888 -90)
		(property "Reference" "R723"
			(at 0 0 270)
			(layer "F.SilkS")
			(hide yes)
			(effects
				(font
					(size 1.27 1.27)
				)
			)
		)
		(property "Value" "4K7R2F-GP"
			(at 0.064008 -3.993896 270)
			(unlocked yes)
			(layer "F.Fab")
			(hide yes)
			(effects
				(font
					(size 1.016 1.016)
					(thickness 0.1524)
				)
			)
		)
		(property "Device Type" "R402H16"
			(at 0.064008 -5.517896 270)
			(unlocked yes)
			(layer "F.Fab")
			(hide yes)
			(effects
				(font
					(size 1.016 1.016)
					(thickness 0.1524)
				)
			)
		)
		(duplicate_pad_numbers_are_jumpers no)
		(fp_line
			(start -0.508 -0.9398)
			(end -0.508 0.9398)
			(stroke
				(width 0.1524)
				(type default)
			)
			(layer "F.SilkS")
		)
		(fp_line
			(start 0.508 -0.9398)
			(end -0.508 -0.9398)
			(stroke
				(width 0.1524)
				(type default)
			)
			(layer "F.SilkS")
		)
		(fp_rect
			(start -0.508 0.9398)
			(end 0.508 -0.9398)
			(stroke
				(width 0)
				(type default)
			)
			(fill no)
			(layer "F.CrtYd")
		)
		(fp_rect
			(start -0.508 0.9398)
			(end 0.508 -0.9398)
			(stroke
				(width 0)
				(type default)
			)
			(fill no)
			(layer "F.Fab")
		)
		(pad "1" smd custom
			(at 0 -0.4445 270)
			(size 0.1397 0.1397)
			(layers "F.Cu" "F.Mask" "F.Paste")
			(net "P5V_STBY")
			(options
				(clearance outline)
				(anchor circle)
			)
			(primitives
				(gr_poly
					(pts
						(arc
							(start -0.1778 -0.2794)
							(mid -0.249642 -0.249642)
							(end -0.2794 -0.1778)
						)
						(arc
							(start -0.2794 0.1778)
							(mid -0.249642 0.249642)
							(end -0.1778 0.2794)
						)
						(arc
							(start 0.1778 0.2794)
							(mid 0.249642 0.249642)
							(end 0.2794 0.1778)
						)
						(arc
							(start 0.2794 -0.1778)
							(mid 0.249642 -0.249642)
							(end 0.1778 -0.2794)
						)
					)
					(width 0)
					(fill yes)
				)
			)
		)
		(pad "2" smd custom
			(at 0 0.4445 270)
			(size 0.1397 0.1397)
			(layers "F.Cu" "F.Mask" "F.Paste")
			(net "P1V15_STBY_PG_G")
			(options
				(clearance outline)
				(anchor circle)
			)
			(primitives
				(gr_poly
					(pts
						(arc
							(start -0.1778 -0.2794)
							(mid -0.249642 -0.249642)
							(end -0.2794 -0.1778)
						)
						(arc
							(start -0.2794 0.1778)
							(mid -0.249642 0.249642)
							(end -0.1778 0.2794)
						)
						(arc
							(start 0.1778 0.2794)
							(mid 0.249642 0.249642)
							(end 0.2794 0.1778)
						)
						(arc
							(start 0.2794 -0.1778)
							(mid 0.249642 -0.249642)
							(end 0.1778 -0.2794)
						)
					)
					(width 0)
					(fill yes)
				)
			)
		)
	)
	(footprint ""
		(layer "F.Cu")
		(at 20.809712 -175.650906)
		(property "Reference" "R533"
			(at 0 0 0)
			(layer "F.SilkS")
			(hide yes)
			(effects
				(font
					(size 1.27 1.27)
				)
			)
		)
		(property "Value" "0R2J-2-GP"
			(at 0.064008 -3.993896 0)
			(unlocked yes)
			(layer "F.Fab")
			(hide yes)
			(effects
				(font
					(size 1.016 1.016)
					(thickness 0.1524)
				)
			)
		)
		(property "Device Type" "R402H16"
			(at 0.064008 -5.517896 0)
			(unlocked yes)
			(layer "F.Fab")
			(hide yes)
			(effects
				(font
					(size 1.016 1.016)
					(thickness 0.1524)
				)
			)
		)
		(duplicate_pad_numbers_are_jumpers no)
		(fp_line
			(start -0.508 -0.9398)
			(end -0.508 0.9398)
			(stroke
				(width 0.1524)
				(type default)
			)
			(layer "F.SilkS")
		)
		(fp_line
			(start 0.508 -0.9398)
			(end -0.508 -0.9398)
			(stroke
				(width 0.1524)
				(type default)
			)
			(layer "F.SilkS")
		)
		(fp_rect
			(start -0.508 0.9398)
			(end 0.508 -0.9398)
			(stroke
				(width 0)
				(type default)
			)
			(fill no)
			(layer "F.CrtYd")
		)
		(fp_rect
			(start -0.508 0.9398)
			(end 0.508 -0.9398)
			(stroke
				(width 0)
				(type default)
			)
			(fill no)
			(layer "F.Fab")
		)
		(pad "1" smd custom
			(at 0 -0.4445)
			(size 0.1397 0.1397)
			(layers "F.Cu" "F.Mask" "F.Paste")
			(net "P5V_STBY")
			(options
				(clearance outline)
				(anchor circle)
			)
			(primitives
				(gr_poly
					(pts
						(arc
							(start -0.1778 -0.2794)
							(mid -0.249642 -0.249642)
							(end -0.2794 -0.1778)
						)
						(arc
							(start -0.2794 0.1778)
							(mid -0.249642 0.249642)
							(end -0.1778 0.2794)
						)
						(arc
							(start 0.1778 0.2794)
							(mid 0.249642 0.249642)
							(end 0.2794 0.1778)
						)
						(arc
							(start 0.2794 -0.1778)
							(mid 0.249642 -0.249642)
							(end 0.1778 -0.2794)
						)
					)
					(width 0)
					(fill yes)
				)
			)
		)
		(pad "2" smd custom
			(at 0 0.4445)
			(size 0.1397 0.1397)
			(layers "F.Cu" "F.Mask" "F.Paste")
			(net "TPS74801_P1V2_STBY_BIAS")
			(options
				(clearance outline)
				(anchor circle)
			)
			(primitives
				(gr_poly
					(pts
						(arc
							(start -0.1778 -0.2794)
							(mid -0.249642 -0.249642)
							(end -0.2794 -0.1778)
						)
						(arc
							(start -0.2794 0.1778)
							(mid -0.249642 0.249642)
							(end -0.1778 0.2794)
						)
						(arc
							(start 0.1778 0.2794)
							(mid 0.249642 0.249642)
							(end 0.2794 0.1778)
						)
						(arc
							(start 0.2794 -0.1778)
							(mid 0.249642 -0.249642)
							(end 0.1778 -0.2794)
						)
					)
					(width 0)
					(fill yes)
				)
			)
		)
	)
	(footprint ""
		(layer "F.Cu")
		(at 8.88111 -135.290052 -90)
		(property "Reference" "R239"
			(at 0 0 270)
			(layer "F.SilkS")
			(hide yes)
			(effects
				(font
					(size 1.27 1.27)
				)
			)
		)
		(property "Value" "0R2J-2-GP"
			(at 0.064008 -3.993896 270)
			(unlocked yes)
			(layer "F.Fab")
			(hide yes)
			(effects
				(font
					(size 1.016 1.016)
					(thickness 0.1524)
				)
			)
		)
		(property "Device Type" "R402H16"
			(at 0.064008 -5.517896 270)
			(unlocked yes)
			(layer "F.Fab")
			(hide yes)
			(effects
				(font
					(size 1.016 1.016)
					(thickness 0.1524)
				)
			)
		)
		(duplicate_pad_numbers_are_jumpers no)
		(fp_line
			(start -0.508 -0.9398)
			(end -0.508 0.9398)
			(stroke
				(width 0.1524)
				(type default)
			)
			(layer "F.SilkS")
		)
		(fp_line
			(start 0.508 -0.9398)
			(end -0.508 -0.9398)
			(stroke
				(width 0.1524)
				(type default)
			)
			(layer "F.SilkS")
		)
		(fp_rect
			(start -0.508 0.9398)
			(end 0.508 -0.9398)
			(stroke
				(width 0)
				(type default)
			)
			(fill no)
			(layer "F.CrtYd")
		)
		(fp_rect
			(start -0.508 0.9398)
			(end 0.508 -0.9398)
			(stroke
				(width 0)
				(type default)
			)
			(fill no)
			(layer "F.Fab")
		)
		(pad "1" smd custom
			(at 0 -0.4445 270)
			(size 0.1397 0.1397)
			(layers "F.Cu" "F.Mask" "F.Paste")
			(net "MEM_PAR")
			(options
				(clearance outline)
				(anchor circle)
			)
			(primitives
				(gr_poly
					(pts
						(arc
							(start -0.1778 -0.2794)
							(mid -0.249642 -0.249642)
							(end -0.2794 -0.1778)
						)
						(arc
							(start -0.2794 0.1778)
							(mid -0.249642 0.249642)
							(end -0.1778 0.2794)
						)
						(arc
							(start 0.1778 0.2794)
							(mid 0.249642 0.249642)
							(end 0.2794 0.1778)
						)
						(arc
							(start 0.2794 -0.1778)
							(mid 0.249642 -0.249642)
							(end 0.1778 -0.2794)
						)
					)
					(width 0)
					(fill yes)
				)
			)
		)
		(pad "2" smd custom
			(at 0 0.4445 270)
			(size 0.1397 0.1397)
			(layers "F.Cu" "F.Mask" "F.Paste")
			(net "GND")
			(options
				(clearance outline)
				(anchor circle)
			)
			(primitives
				(gr_poly
					(pts
						(arc
							(start -0.1778 -0.2794)
							(mid -0.249642 -0.249642)
							(end -0.2794 -0.1778)
						)
						(arc
							(start -0.2794 0.1778)
							(mid -0.249642 0.249642)
							(end -0.1778 0.2794)
						)
						(arc
							(start 0.1778 0.2794)
							(mid 0.249642 0.249642)
							(end 0.2794 0.1778)
						)
						(arc
							(start 0.2794 -0.1778)
							(mid 0.249642 -0.249642)
							(end 0.1778 -0.2794)
						)
					)
					(width 0)
					(fill yes)
				)
			)
		)
	)
	(footprint ""
		(layer "F.Cu")
		(at 53.3273 -161.0614 -90)
		(property "Reference" "C84"
			(at 0 0 270)
			(layer "F.SilkS")
			(hide yes)
			(effects
				(font
					(size 1.27 1.27)
				)
			)
		)
		(property "Value" "SCD1U16V2KX-3GP"
			(at 1.1811 -2.7051 270)
			(unlocked yes)
			(layer "F.Fab")
			(hide yes)
			(effects
				(font
					(size 1.016 1.016)
					(thickness 0.1524)
				)
			)
		)
		(property "Device Type" "C402H22"
			(at 1.1811 -4.2291 270)
			(unlocked yes)
			(layer "F.Fab")
			(hide yes)
			(effects
				(font
					(size 1.016 1.016)
					(thickness 0.1524)
				)
			)
		)
		(duplicate_pad_numbers_are_jumpers no)
		(fp_rect
			(start -0.4318 0.9525)
			(end 0.4318 -0.9525)
			(stroke
				(width 0)
				(type default)
			)
			(fill no)
			(layer "F.CrtYd")
		)
		(fp_rect
			(start -0.4318 0.9525)
			(end 0.4318 -0.9525)
			(stroke
				(width 0)
				(type default)
			)
			(fill no)
			(layer "F.Fab")
		)
		(pad "1" smd custom
			(at 0 -0.4445 270)
			(size 0.1524 0.1524)
			(layers "F.Cu" "F.Mask" "F.Paste")
			(net "ADCAV33")
			(options
				(clearance outline)
				(anchor circle)
			)
			(primitives
				(gr_poly
					(pts
						(arc
							(start 0.3048 -0.2032)
							(mid 0.275042 -0.275042)
							(end 0.2032 -0.3048)
						)
						(arc
							(start -0.2032 -0.3048)
							(mid -0.275042 -0.275042)
							(end -0.3048 -0.2032)
						)
						(arc
							(start -0.3048 0.2032)
							(mid -0.275042 0.275042)
							(end -0.2032 0.3048)
						)
						(arc
							(start 0.2032 0.3048)
							(mid 0.275042 0.275042)
							(end 0.3048 0.2032)
						)
					)
					(width 0)
					(fill yes)
				)
			)
		)
		(pad "2" smd custom
			(at 0 0.4445 270)
			(size 0.1524 0.1524)
			(layers "F.Cu" "F.Mask" "F.Paste")
			(net "ADCVREFFP")
			(options
				(clearance outline)
				(anchor circle)
			)
			(primitives
				(gr_poly
					(pts
						(arc
							(start 0.3048 -0.2032)
							(mid 0.275042 -0.275042)
							(end 0.2032 -0.3048)
						)
						(arc
							(start -0.2032 -0.3048)
							(mid -0.275042 -0.275042)
							(end -0.3048 -0.2032)
						)
						(arc
							(start -0.3048 0.2032)
							(mid -0.275042 0.275042)
							(end -0.2032 0.3048)
						)
						(arc
							(start 0.2032 0.3048)
							(mid 0.275042 0.275042)
							(end 0.3048 0.2032)
						)
					)
					(width 0)
					(fill yes)
				)
			)
		)
	)
	(footprint ""
		(layer "F.Cu")
		(at 29.367226 -180.33873 180)
		(property "Reference" "C182"
			(at 0 0 180)
			(layer "F.SilkS")
			(hide yes)
			(effects
				(font
					(size 1.27 1.27)
				)
			)
		)
		(property "Value" "SC1U16V3KX-5GP"
			(at 0 -2.8194 180)
			(unlocked yes)
			(layer "F.Fab")
			(hide yes)
			(effects
				(font
					(size 1.016 1.016)
					(thickness 0.1524)
				)
			)
		)
		(property "Device Type" "C603H36"
			(at 0 -4.3434 180)
			(unlocked yes)
			(layer "F.Fab")
			(hide yes)
			(effects
				(font
					(size 1.016 1.016)
					(thickness 0.1524)
				)
			)
		)
		(duplicate_pad_numbers_are_jumpers no)
		(fp_line
			(start 0.508 0)
			(end -0.508 0)
			(stroke
				(width 0.2032)
				(type default)
			)
			(layer "F.SilkS")
		)
		(fp_rect
			(start -0.5842 1.3335)
			(end 0.5842 -1.3335)
			(stroke
				(width 0)
				(type default)
			)
			(fill no)
			(layer "F.CrtYd")
		)
		(fp_rect
			(start -0.5842 1.3335)
			(end 0.5842 -1.3335)
			(stroke
				(width 0)
				(type default)
			)
			(fill no)
			(layer "F.Fab")
		)
		(pad "1" smd custom
			(at 0 -0.762 180)
			(size 0.2159 0.2159)
			(layers "F.Cu" "F.Mask" "F.Paste")
			(net "GND")
			(options
				(clearance outline)
				(anchor circle)
			)
			(primitives
				(gr_poly
					(pts
						(arc
							(start -0.3302 -0.4318)
							(mid -0.402042 -0.402042)
							(end -0.4318 -0.3302)
						)
						(arc
							(start -0.4318 0.3302)
							(mid -0.402042 0.402042)
							(end -0.3302 0.4318)
						)
						(arc
							(start 0.3302 0.4318)
							(mid 0.402042 0.402042)
							(end 0.4318 0.3302)
						)
						(arc
							(start 0.4318 -0.3302)
							(mid 0.402042 -0.402042)
							(end 0.3302 -0.4318)
						)
					)
					(width 0)
					(fill yes)
				)
			)
		)
		(pad "2" smd custom
			(at 0 0.762 180)
			(size 0.2159 0.2159)
			(layers "F.Cu" "F.Mask" "F.Paste")
			(net "P3V3_STBY_VREG")
			(options
				(clearance outline)
				(anchor circle)
			)
			(primitives
				(gr_poly
					(pts
						(arc
							(start -0.3302 -0.4318)
							(mid -0.402042 -0.402042)
							(end -0.4318 -0.3302)
						)
						(arc
							(start -0.4318 0.3302)
							(mid -0.402042 0.402042)
							(end -0.3302 0.4318)
						)
						(arc
							(start 0.3302 0.4318)
							(mid 0.402042 0.402042)
							(end 0.4318 0.3302)
						)
						(arc
							(start 0.4318 -0.3302)
							(mid 0.402042 -0.402042)
							(end 0.3302 -0.4318)
						)
					)
					(width 0)
					(fill yes)
				)
			)
		)
	)
)
